(kicad_pcb
	(version 20260206)
	(generator "pcbnew")
	(generator_version "10.0")
	(general
		(thickness 1.6)
		(legacy_teardrops no)
	)
	(paper "A4")
	(title_block
		(title "pdpb — Lightning_PDPB_BRD.brd")
		(comment 1 "Lightning (Wiwynn / Facebook NVMe JBOF) / footprints 30-36 of 1140")
	)
	(layers
		(0 "F.Cu" signal "TOP")
		(4 "In1.Cu" signal "L2GND")
		(6 "In2.Cu" signal "L3")
		(8 "In3.Cu" signal "L4VCC")
		(10 "In4.Cu" signal "L5VCC")
		(12 "In5.Cu" signal "L6")
		(14 "In6.Cu" signal "L7GND")
		(2 "B.Cu" signal "BOTTOM")
		(9 "F.Adhes" user "F.Adhesive")
		(11 "B.Adhes" user "B.Adhesive")
		(13 "F.Paste" user "Package Geometry/Pastemask Top")
		(15 "B.Paste" user "Package Geometry/Pastemask Bottom")
		(5 "F.SilkS" user "Ref Des/Silkscreen Top")
		(7 "B.SilkS" user "Ref Des/Silkscreen Bottom")
		(1 "F.Mask" user "Board Geometry/Soldermask Top")
		(3 "B.Mask" user "Board Geometry/Soldermask Bottom")
		(17 "Dwgs.User" user "User.Drawings")
		(19 "Cmts.User" user "User.Comments")
		(21 "Eco1.User" user "User.Eco1")
		(23 "Eco2.User" user "User.Eco2")
		(25 "Edge.Cuts" user "Board Geometry/Outline")
		(27 "Margin" user)
		(31 "F.CrtYd" user "Package Geometry/Place Bound Top")
		(29 "B.CrtYd" user "Package Geometry/Place Bound Bottom")
		(35 "F.Fab" user "Ref Des/Assembly Top")
		(33 "B.Fab" user "Ref Des/Assembly Bottom")
	)
	(footprint ""
		(layer "F.Cu")
		(at 82.931 -106.934 90)
		(property "Reference" "SR954"
			(at 0 0 90)
			(layer "F.SilkS")
			(hide yes)
			(effects
				(font
					(size 1.27 1.27)
				)
			)
		)
		(property "Value" "4K7R2F-GP"
			(at 0.064008 -3.993896 90)
			(unlocked yes)
			(layer "F.Fab")
			(hide yes)
			(effects
				(font
					(size 1.016 1.016)
					(thickness 0.1524)
				)
			)
		)
		(property "Device Type" "R402H16"
			(at 0.064008 -5.517896 90)
			(unlocked yes)
			(layer "F.Fab")
			(hide yes)
			(effects
				(font
					(size 1.016 1.016)
					(thickness 0.1524)
				)
			)
		)
		(duplicate_pad_numbers_are_jumpers no)
		(fp_line
			(start 0.508 -0.9398)
			(end -0.508 -0.9398)
			(stroke
				(width 0.1524)
				(type default)
			)
			(layer "F.SilkS")
		)
		(fp_line
			(start -0.508 -0.9398)
			(end -0.508 0.9398)
			(stroke
				(width 0.1524)
				(type default)
			)
			(layer "F.SilkS")
		)
		(fp_rect
			(start -0.508 0.9398)
			(end 0.508 -0.9398)
			(stroke
				(width 0)
				(type default)
			)
			(fill no)
			(layer "F.CrtYd")
		)
		(fp_rect
			(start -0.508 0.9398)
			(end 0.508 -0.9398)
			(stroke
				(width 0)
				(type default)
			)
			(fill no)
			(layer "F.Fab")
		)
		(pad "1" smd custom
			(at 0 -0.4445 90)
			(size 0.1397 0.1397)
			(layers "F.Cu" "F.Mask" "F.Paste")
			(net "VDD_DIFF_4")
			(options
				(clearance outline)
				(anchor circle)
			)
			(primitives
				(gr_poly
					(pts
						(arc
							(start -0.1778 -0.2794)
							(mid -0.249642 -0.249642)
							(end -0.2794 -0.1778)
						)
						(arc
							(start -0.2794 0.1778)
							(mid -0.249642 0.249642)
							(end -0.1778 0.2794)
						)
						(arc
							(start 0.1778 0.2794)
							(mid 0.249642 0.249642)
							(end 0.2794 0.1778)
						)
						(arc
							(start 0.2794 -0.1778)
							(mid 0.249642 -0.249642)
							(end 0.1778 -0.2794)
						)
					)
					(width 0)
					(fill yes)
				)
			)
		)
		(pad "2" smd custom
			(at 0 0.4445 90)
			(size 0.1397 0.1397)
			(layers "F.Cu" "F.Mask" "F.Paste")
			(net "CLK_BUF_EU4_100M_133M#")
			(options
				(clearance outline)
				(anchor circle)
			)
			(primitives
				(gr_poly
					(pts
						(arc
							(start -0.1778 -0.2794)
							(mid -0.249642 -0.249642)
							(end -0.2794 -0.1778)
						)
						(arc
							(start -0.2794 0.1778)
							(mid -0.249642 0.249642)
							(end -0.1778 0.2794)
						)
						(arc
							(start 0.1778 0.2794)
							(mid 0.249642 0.249642)
							(end 0.2794 0.1778)
						)
						(arc
							(start 0.2794 -0.1778)
							(mid 0.249642 -0.249642)
							(end 0.1778 -0.2794)
						)
					)
					(width 0)
					(fill yes)
				)
			)
		)
	)
	(footprint ""
		(layer "F.Cu")
		(at 82.931 -215.138 90)
		(property "Reference" "SR953"
			(at 0 0 90)
			(layer "F.SilkS")
			(hide yes)
			(effects
				(font
					(size 1.27 1.27)
				)
			)
		)
		(property "Value" "4K7R2F-GP"
			(at 0.064008 -3.993896 90)
			(unlocked yes)
			(layer "F.Fab")
			(hide yes)
			(effects
				(font
					(size 1.016 1.016)
					(thickness 0.1524)
				)
			)
		)
		(property "Device Type" "R402H16"
			(at 0.064008 -5.517896 90)
			(unlocked yes)
			(layer "F.Fab")
			(hide yes)
			(effects
				(font
					(size 1.016 1.016)
					(thickness 0.1524)
				)
			)
		)
		(duplicate_pad_numbers_are_jumpers no)
		(fp_line
			(start 0.508 -0.9398)
			(end -0.508 -0.9398)
			(stroke
				(width 0.1524)
				(type default)
			)
			(layer "F.SilkS")
		)
		(fp_line
			(start -0.508 -0.9398)
			(end -0.508 0.9398)
			(stroke
				(width 0.1524)
				(type default)
			)
			(layer "F.SilkS")
		)
		(fp_rect
			(start -0.508 0.9398)
			(end 0.508 -0.9398)
			(stroke
				(width 0)
				(type default)
			)
			(fill no)
			(layer "F.CrtYd")
		)
		(fp_rect
			(start -0.508 0.9398)
			(end 0.508 -0.9398)
			(stroke
				(width 0)
				(type default)
			)
			(fill no)
			(layer "F.Fab")
		)
		(pad "1" smd custom
			(at 0 -0.4445 90)
			(size 0.1397 0.1397)
			(layers "F.Cu" "F.Mask" "F.Paste")
			(net "VDD_DIFF_3")
			(options
				(clearance outline)
				(anchor circle)
			)
			(primitives
				(gr_poly
					(pts
						(arc
							(start -0.1778 -0.2794)
							(mid -0.249642 -0.249642)
							(end -0.2794 -0.1778)
						)
						(arc
							(start -0.2794 0.1778)
							(mid -0.249642 0.249642)
							(end -0.1778 0.2794)
						)
						(arc
							(start 0.1778 0.2794)
							(mid 0.249642 0.249642)
							(end 0.2794 0.1778)
						)
						(arc
							(start 0.2794 -0.1778)
							(mid 0.249642 -0.249642)
							(end 0.1778 -0.2794)
						)
					)
					(width 0)
					(fill yes)
				)
			)
		)
		(pad "2" smd custom
			(at 0 0.4445 90)
			(size 0.1397 0.1397)
			(layers "F.Cu" "F.Mask" "F.Paste")
			(net "CLK_BUF_EU3_HIBW_BYPM_LOBW#")
			(options
				(clearance outline)
				(anchor circle)
			)
			(primitives
				(gr_poly
					(pts
						(arc
							(start -0.1778 -0.2794)
							(mid -0.249642 -0.249642)
							(end -0.2794 -0.1778)
						)
						(arc
							(start -0.2794 0.1778)
							(mid -0.249642 0.249642)
							(end -0.1778 0.2794)
						)
						(arc
							(start 0.1778 0.2794)
							(mid 0.249642 0.249642)
							(end 0.2794 0.1778)
						)
						(arc
							(start 0.2794 -0.1778)
							(mid 0.249642 -0.249642)
							(end 0.1778 -0.2794)
						)
					)
					(width 0)
					(fill yes)
				)
			)
		)
	)
	(footprint ""
		(layer "F.Cu")
		(at 102.616 -306.705 90)
		(property "Reference" "R9074"
			(at 0 0 90)
			(layer "F.SilkS")
			(hide yes)
			(effects
				(font
					(size 1.27 1.27)
				)
			)
		)
		(property "Value" "27R2F-GP"
			(at 0.064008 -3.993896 90)
			(unlocked yes)
			(layer "F.Fab")
			(hide yes)
			(effects
				(font
					(size 1.016 1.016)
					(thickness 0.1524)
				)
			)
		)
		(property "Device Type" "R402H16"
			(at 0.064008 -5.517896 90)
			(unlocked yes)
			(layer "F.Fab")
			(hide yes)
			(effects
				(font
					(size 1.016 1.016)
					(thickness 0.1524)
				)
			)
		)
		(duplicate_pad_numbers_are_jumpers no)
		(fp_line
			(start 0.508 -0.9398)
			(end -0.508 -0.9398)
			(stroke
				(width 0.1524)
				(type default)
			)
			(layer "F.SilkS")
		)
		(fp_line
			(start -0.508 -0.9398)
			(end -0.508 0.9398)
			(stroke
				(width 0.1524)
				(type default)
			)
			(layer "F.SilkS")
		)
		(fp_rect
			(start -0.508 0.9398)
			(end 0.508 -0.9398)
			(stroke
				(width 0)
				(type default)
			)
			(fill no)
			(layer "F.CrtYd")
		)
		(fp_rect
			(start -0.508 0.9398)
			(end 0.508 -0.9398)
			(stroke
				(width 0)
				(type default)
			)
			(fill no)
			(layer "F.Fab")
		)
		(pad "1" smd custom
			(at 0 -0.4445 90)
			(size 0.1397 0.1397)
			(layers "F.Cu" "F.Mask" "F.Paste")
			(net "PE_CLK_100M_DR1_2_R_P")
			(options
				(clearance outline)
				(anchor circle)
			)
			(primitives
				(gr_poly
					(pts
						(arc
							(start -0.1778 -0.2794)
							(mid -0.249642 -0.249642)
							(end -0.2794 -0.1778)
						)
						(arc
							(start -0.2794 0.1778)
							(mid -0.249642 0.249642)
							(end -0.1778 0.2794)
						)
						(arc
							(start 0.1778 0.2794)
							(mid 0.249642 0.249642)
							(end 0.2794 0.1778)
						)
						(arc
							(start 0.2794 -0.1778)
							(mid 0.249642 -0.249642)
							(end 0.1778 -0.2794)
						)
					)
					(width 0)
					(fill yes)
				)
			)
		)
		(pad "2" smd custom
			(at 0 0.4445 90)
			(size 0.1397 0.1397)
			(layers "F.Cu" "F.Mask" "F.Paste")
			(net "PE_CLK100M_DR1_2_P")
			(options
				(clearance outline)
				(anchor circle)
			)
			(primitives
				(gr_poly
					(pts
						(arc
							(start -0.1778 -0.2794)
							(mid -0.249642 -0.249642)
							(end -0.2794 -0.1778)
						)
						(arc
							(start -0.2794 0.1778)
							(mid -0.249642 0.249642)
							(end -0.1778 0.2794)
						)
						(arc
							(start 0.1778 0.2794)
							(mid 0.249642 0.249642)
							(end 0.2794 0.1778)
						)
						(arc
							(start 0.2794 -0.1778)
							(mid 0.249642 -0.249642)
							(end 0.1778 -0.2794)
						)
					)
					(width 0)
					(fill yes)
				)
			)
		)
	)
	(footprint ""
		(layer "F.Cu")
		(at 227.391214 -142.343632 90)
		(property "Reference" "R9934"
			(at 0 0 90)
			(layer "F.SilkS")
			(hide yes)
			(effects
				(font
					(size 1.27 1.27)
				)
			)
		)
		(property "Value" "4K7R2J-2-GP"
			(at 0.064008 -3.993896 90)
			(unlocked yes)
			(layer "F.Fab")
			(hide yes)
			(effects
				(font
					(size 1.016 1.016)
					(thickness 0.1524)
				)
			)
		)
		(property "Device Type" "R402H16"
			(at 0.064008 -5.517896 90)
			(unlocked yes)
			(layer "F.Fab")
			(hide yes)
			(effects
				(font
					(size 1.016 1.016)
					(thickness 0.1524)
				)
			)
		)
		(duplicate_pad_numbers_are_jumpers no)
		(fp_line
			(start 0.508 -0.9398)
			(end -0.508 -0.9398)
			(stroke
				(width 0.1524)
				(type default)
			)
			(layer "F.SilkS")
		)
		(fp_line
			(start -0.508 -0.9398)
			(end -0.508 0.9398)
			(stroke
				(width 0.1524)
				(type default)
			)
			(layer "F.SilkS")
		)
		(fp_rect
			(start -0.508 0.9398)
			(end 0.508 -0.9398)
			(stroke
				(width 0)
				(type default)
			)
			(fill no)
			(layer "F.CrtYd")
		)
		(fp_rect
			(start -0.508 0.9398)
			(end 0.508 -0.9398)
			(stroke
				(width 0)
				(type default)
			)
			(fill no)
			(layer "F.Fab")
		)
		(pad "1" smd custom
			(at 0 -0.4445 90)
			(size 0.1397 0.1397)
			(layers "F.Cu" "F.Mask" "F.Paste")
			(net "P3V3")
			(options
				(clearance outline)
				(anchor circle)
			)
			(primitives
				(gr_poly
					(pts
						(arc
							(start -0.1778 -0.2794)
							(mid -0.249642 -0.249642)
							(end -0.2794 -0.1778)
						)
						(arc
							(start -0.2794 0.1778)
							(mid -0.249642 0.249642)
							(end -0.1778 0.2794)
						)
						(arc
							(start 0.1778 0.2794)
							(mid 0.249642 0.249642)
							(end 0.2794 0.1778)
						)
						(arc
							(start 0.2794 -0.1778)
							(mid 0.249642 -0.249642)
							(end 0.1778 -0.2794)
						)
					)
					(width 0)
					(fill yes)
				)
			)
		)
		(pad "2" smd custom
			(at 0 0.4445 90)
			(size 0.1397 0.1397)
			(layers "F.Cu" "F.Mask" "F.Paste")
			(net "SSD_ACT_DR3_MOS_N")
			(options
				(clearance outline)
				(anchor circle)
			)
			(primitives
				(gr_poly
					(pts
						(arc
							(start -0.1778 -0.2794)
							(mid -0.249642 -0.249642)
							(end -0.2794 -0.1778)
						)
						(arc
							(start -0.2794 0.1778)
							(mid -0.249642 0.249642)
							(end -0.1778 0.2794)
						)
						(arc
							(start 0.1778 0.2794)
							(mid 0.249642 0.249642)
							(end 0.2794 0.1778)
						)
						(arc
							(start 0.2794 -0.1778)
							(mid 0.249642 -0.249642)
							(end 0.1778 -0.2794)
						)
					)
					(width 0)
					(fill yes)
				)
			)
		)
	)
	(footprint ""
		(layer "F.Cu")
		(at 31.10103 -187.684918 180)
		(property "Reference" "SR1108"
			(at 0 0 180)
			(layer "F.SilkS")
			(hide yes)
			(effects
				(font
					(size 1.27 1.27)
				)
			)
		)
		(property "Value" "4K7R2F-GP"
			(at 0.064008 -3.993896 180)
			(unlocked yes)
			(layer "F.Fab")
			(hide yes)
			(effects
				(font
					(size 1.016 1.016)
					(thickness 0.1524)
				)
			)
		)
		(property "Device Type" "R402H16"
			(at 0.064008 -5.517896 180)
			(unlocked yes)
			(layer "F.Fab")
			(hide yes)
			(effects
				(font
					(size 1.016 1.016)
					(thickness 0.1524)
				)
			)
		)
		(duplicate_pad_numbers_are_jumpers no)
		(fp_line
			(start 0.508 -0.9398)
			(end -0.508 -0.9398)
			(stroke
				(width 0.1524)
				(type default)
			)
			(layer "F.SilkS")
		)
		(fp_line
			(start -0.508 -0.9398)
			(end -0.508 0.9398)
			(stroke
				(width 0.1524)
				(type default)
			)
			(layer "F.SilkS")
		)
		(fp_rect
			(start -0.508 0.9398)
			(end 0.508 -0.9398)
			(stroke
				(width 0)
				(type default)
			)
			(fill no)
			(layer "F.CrtYd")
		)
		(fp_rect
			(start -0.508 0.9398)
			(end 0.508 -0.9398)
			(stroke
				(width 0)
				(type default)
			)
			(fill no)
			(layer "F.Fab")
		)
		(pad "1" smd custom
			(at 0 -0.4445 180)
			(size 0.1397 0.1397)
			(layers "F.Cu" "F.Mask" "F.Paste")
			(net "DUALPORTEN#8")
			(options
				(clearance outline)
				(anchor circle)
			)
			(primitives
				(gr_poly
					(pts
						(arc
							(start -0.1778 -0.2794)
							(mid -0.249642 -0.249642)
							(end -0.2794 -0.1778)
						)
						(arc
							(start -0.2794 0.1778)
							(mid -0.249642 0.249642)
							(end -0.1778 0.2794)
						)
						(arc
							(start 0.1778 0.2794)
							(mid 0.249642 0.249642)
							(end 0.2794 0.1778)
						)
						(arc
							(start 0.2794 -0.1778)
							(mid 0.249642 -0.249642)
							(end 0.1778 -0.2794)
						)
					)
					(width 0)
					(fill yes)
				)
			)
		)
		(pad "2" smd custom
			(at 0 0.4445 180)
			(size 0.1397 0.1397)
			(layers "F.Cu" "F.Mask" "F.Paste")
			(net "GND")
			(options
				(clearance outline)
				(anchor circle)
			)
			(primitives
				(gr_poly
					(pts
						(arc
							(start -0.1778 -0.2794)
							(mid -0.249642 -0.249642)
							(end -0.2794 -0.1778)
						)
						(arc
							(start -0.2794 0.1778)
							(mid -0.249642 0.249642)
							(end -0.1778 0.2794)
						)
						(arc
							(start 0.1778 0.2794)
							(mid 0.249642 0.249642)
							(end 0.2794 0.1778)
						)
						(arc
							(start 0.2794 -0.1778)
							(mid 0.249642 -0.249642)
							(end 0.1778 -0.2794)
						)
					)
					(width 0)
					(fill yes)
				)
			)
		)
	)
	(footprint ""
		(layer "F.Cu")
		(at 228.499924 -453.099932)
		(property "Reference" "LED100"
			(at 0 0 0)
			(layer "F.SilkS")
			(hide yes)
			(effects
				(font
					(size 1.27 1.27)
				)
			)
		)
		(property "Value" "LED-RB-4-GP"
			(at 5.88899 1.80848 0)
			(unlocked yes)
			(layer "F.Fab")
			(hide yes)
			(effects
				(font
					(size 1.016 1.016)
					(thickness 0.1524)
				)
			)
		)
		(property "Device Type" "LED1613-4PH20"
			(at 5.88899 0.28448 0)
			(unlocked yes)
			(layer "F.Fab")
			(hide yes)
			(effects
				(font
					(size 1.016 1.016)
					(thickness 0.1524)
				)
			)
		)
		(duplicate_pad_numbers_are_jumpers no)
		(fp_line
			(start -1.4478 -0.9652)
			(end 1.4478 -0.9652)
			(stroke
				(width 0.1524)
				(type default)
			)
			(layer "F.SilkS")
		)
		(fp_line
			(start -1.4478 0.9652)
			(end -1.4478 -0.9652)
			(stroke
				(width 0.1524)
				(type default)
			)
			(layer "F.SilkS")
		)
		(fp_line
			(start -1.4478 0.9652)
			(end -1.4478 -0.9652)
			(stroke
				(width 0.508)
				(type default)
			)
			(layer "F.SilkS")
		)
		(fp_line
			(start 1.4478 -0.9652)
			(end 1.4478 0.9652)
			(stroke
				(width 0.1524)
				(type default)
			)
			(layer "F.SilkS")
		)
		(fp_line
			(start 1.4478 0.9652)
			(end -1.4478 0.9652)
			(stroke
				(width 0.1524)
				(type default)
			)
			(layer "F.SilkS")
		)
		(fp_rect
			(start -0.8001 0.6477)
			(end 0.8001 -0.6477)
			(stroke
				(width 0)
				(type default)
			)
			(fill no)
			(layer "F.CrtYd")
		)
		(fp_poly
			(pts
				(xy -1.7018 1.2192) (xy -1.7018 -0.06223) (xy -0.8001 -0.06223) (xy -0.8001 0.6477) (xy 0.8001 0.6477)
				(xy 0.8001 -0.6477) (xy -0.8001 -0.6477) (xy -0.8001 -0.0635) (xy -1.7018 -0.0635) (xy -1.7018 -1.2192)
				(xy 1.7018 -1.2192) (xy 1.7018 1.2192)
			)
			(stroke
				(width 0)
				(type default)
			)
			(fill no)
			(layer "F.CrtYd")
		)
		(fp_rect
			(start -1.7018 1.2192)
			(end 1.7018 -1.2192)
			(stroke
				(width 0)
				(type default)
			)
			(fill no)
			(layer "F.Fab")
		)
		(pad "1" smd rect
			(at -0.73025 0.4064)
			(size 0.9144 0.6096)
			(layers "F.Cu" "F.Mask" "F.Paste")
			(net "SSD_ACT_DR0_MOS_N")
		)
		(pad "2" smd rect
			(at -0.73025 -0.4064)
			(size 0.9144 0.6096)
			(layers "F.Cu" "F.Mask" "F.Paste")
			(net "ATTN_LED_DR0_MOS_N")
		)
		(pad "3" smd rect
			(at 0.73025 -0.4064)
			(size 0.9144 0.6096)
			(layers "F.Cu" "F.Mask" "F.Paste")
			(net "DRV_ATTN_0")
		)
		(pad "4" smd rect
			(at 0.73025 0.4064)
			(size 0.9144 0.6096)
			(layers "F.Cu" "F.Mask" "F.Paste")
			(net "DRV_ACT_0")
		)
	)
	(footprint ""
		(layer "F.Cu")
		(at 24.003 -94.234)
		(property "Reference" "R9769"
			(at 0 0 0)
			(layer "F.SilkS")
			(hide yes)
			(effects
				(font
					(size 1.27 1.27)
				)
			)
		)
		(property "Value" "4K7R2J-2-GP"
			(at 0.064008 -3.993896 0)
			(unlocked yes)
			(layer "F.Fab")
			(hide yes)
			(effects
				(font
					(size 1.016 1.016)
					(thickness 0.1524)
				)
			)
		)
		(property "Device Type" "R402H16"
			(at 0.064008 -5.517896 0)
			(unlocked yes)
			(layer "F.Fab")
			(hide yes)
			(effects
				(font
					(size 1.016 1.016)
					(thickness 0.1524)
				)
			)
		)
		(duplicate_pad_numbers_are_jumpers no)
		(fp_line
			(start -0.508 -0.9398)
			(end -0.508 0.9398)
			(stroke
				(width 0.1524)
				(type default)
			)
			(layer "F.SilkS")
		)
		(fp_line
			(start 0.508 -0.9398)
			(end -0.508 -0.9398)
			(stroke
				(width 0.1524)
				(type default)
			)
			(layer "F.SilkS")
		)
		(fp_rect
			(start -0.508 0.9398)
			(end 0.508 -0.9398)
			(stroke
				(width 0)
				(type default)
			)
			(fill no)
			(layer "F.CrtYd")
		)
		(fp_rect
			(start -0.508 0.9398)
			(end 0.508 -0.9398)
			(stroke
				(width 0)
				(type default)
			)
			(fill no)
			(layer "F.Fab")
		)
		(pad "1" smd custom
			(at 0 -0.4445)
			(size 0.1397 0.1397)
			(layers "F.Cu" "F.Mask" "F.Paste")
			(net "SSD9_PWREN")
			(options
				(clearance outline)
				(anchor circle)
			)
			(primitives
				(gr_poly
					(pts
						(arc
							(start -0.1778 -0.2794)
							(mid -0.249642 -0.249642)
							(end -0.2794 -0.1778)
						)
						(arc
							(start -0.2794 0.1778)
							(mid -0.249642 0.249642)
							(end -0.1778 0.2794)
						)
						(arc
							(start 0.1778 0.2794)
							(mid 0.249642 0.249642)
							(end 0.2794 0.1778)
						)
						(arc
							(start 0.2794 -0.1778)
							(mid 0.249642 -0.249642)
							(end 0.1778 -0.2794)
						)
					)
					(width 0)
					(fill yes)
				)
			)
		)
		(pad "2" smd custom
			(at 0 0.4445)
			(size 0.1397 0.1397)
			(layers "F.Cu" "F.Mask" "F.Paste")
			(net "GND")
			(options
				(clearance outline)
				(anchor circle)
			)
			(primitives
				(gr_poly
					(pts
						(arc
							(start -0.1778 -0.2794)
							(mid -0.249642 -0.249642)
							(end -0.2794 -0.1778)
						)
						(arc
							(start -0.2794 0.1778)
							(mid -0.249642 0.249642)
							(end -0.1778 0.2794)
						)
						(arc
							(start 0.1778 0.2794)
							(mid 0.249642 0.249642)
							(end 0.2794 0.1778)
						)
						(arc
							(start 0.2794 -0.1778)
							(mid 0.249642 -0.249642)
							(end 0.1778 -0.2794)
						)
					)
					(width 0)
					(fill yes)
				)
			)
		)
	)
)
